# T6G (Grand Teton) — schematic netlist excerpt (pin names and nets, part order shuffled) for the footprints in the layout excerpt that follows; sources: Cadence DE-HDL packaged netlist, KiCad conversion of 04192023_DAF0TMB3IC0_F0TG_MB_C_brd_V02_OCP.brd

PR3844  Q_RES  71.5K 1% CHIP  pkg 0402LF  page 135 : A = P3V3_OCP_MODE_1 ; B = GND
R1059  Q_RES  1K 1% EMPTY  pkg 0201LF  page 298 : A = P1V8_CPU0_RT_1D ; B = RT_CPU0_P2_ADDR1
R6184  Q_RES  0 5% CHIP  pkg 0402LF  page 82 : A = FM_SEC_MUX_SEL ; B = FM_SEC_MUX_R_SEL

(kicad_pcb
	(version 20260206)
	(generator "pcbnew")
	(generator_version "10.0")
	(general
		(thickness 1.6)
		(legacy_teardrops no)
	)
	(paper "A4")
	(title_block
		(title "04192023_DAF0TMB3IC0_F0TG_MB_C_brd_V02_OCP.brd")
		(comment 1 "Grand Teton / footprints 1666-1668 of 8354")
	)
	(layers
		(0 "F.Cu" signal "TOP")
		(4 "In1.Cu" signal "GND")
		(6 "In2.Cu" signal "IN1")
		(8 "In3.Cu" signal "GND1")
		(10 "In4.Cu" signal "IN2")
		(12 "In5.Cu" signal "GND2")
		(14 "In6.Cu" signal "IN3")
		(16 "In7.Cu" signal "GND3")
		(18 "In8.Cu" signal "VCC")
		(20 "In9.Cu" signal "VCC1")
		(22 "In10.Cu" signal "GND4")
		(24 "In11.Cu" signal "IN4")
		(26 "In12.Cu" signal "GND5")
		(28 "In13.Cu" signal "IN5")
		(30 "In14.Cu" signal "GND6")
		(32 "In15.Cu" signal "IN6")
		(34 "In16.Cu" signal "GND7")
		(2 "B.Cu" signal "BOTTOM")
		(9 "F.Adhes" user "F.Adhesive")
		(11 "B.Adhes" user "B.Adhesive")
		(13 "F.Paste" user "Package Geometry/Pastemask Top")
		(15 "B.Paste" user "Package Geometry/Pastemask Bottom")
		(5 "F.SilkS" user "Ref Des/Silkscreen Top")
		(7 "B.SilkS" user "Ref Des/Silkscreen Bottom")
		(1 "F.Mask" user "Board Geometry/Soldermask Top")
		(3 "B.Mask" user "Board Geometry/Soldermask Bottom")
		(17 "Dwgs.User" user "User.Drawings")
		(19 "Cmts.User" user "User.Comments")
		(21 "Eco1.User" user "User.Eco1")
		(23 "Eco2.User" user "User.Eco2")
		(25 "Edge.Cuts" user "Board Geometry/Outline")
		(27 "Margin" user)
		(31 "F.CrtYd" user "Package Geometry/Place Bound Top")
		(29 "B.CrtYd" user "Package Geometry/Place Bound Bottom")
		(35 "F.Fab" user "Ref Des/Assembly Top")
		(33 "B.Fab" user "Ref Des/Assembly Bottom")
	)
	(footprint ""
		(layer "F.Cu")
		(at 422.55694 -101.270308 -90)
		(property "Reference" "PR3844"
			(at 0 0 270)
			(layer "F.SilkS")
			(hide yes)
			(effects
				(font
					(size 1.27 1.27)
				)
			)
		)
		(property "Value" ""
			(at 0 0 270)
			(layer "F.Fab")
			(effects
				(font
					(size 1.27 1.27)
				)
			)
		)
		(duplicate_pad_numbers_are_jumpers no)
		(fp_line
			(start -0.7874 0.4064)
			(end -0.7874 -0.4064)
			(stroke
				(width 0.1524)
				(type default)
			)
			(layer "F.SilkS")
		)
		(fp_line
			(start 0.7874 0.4064)
			(end -0.7874 0.4064)
			(stroke
				(width 0.1524)
				(type default)
			)
			(layer "F.SilkS")
		)
		(fp_line
			(start -0.7874 -0.4064)
			(end 0.7874 -0.4064)
			(stroke
				(width 0.1524)
				(type default)
			)
			(layer "F.SilkS")
		)
		(fp_line
			(start 0.7874 -0.4064)
			(end 0.7874 0.4064)
			(stroke
				(width 0.1524)
				(type default)
			)
			(layer "F.SilkS")
		)
		(fp_line
			(start -0.67945 0.3048)
			(end -0.67945 -0.305054)
			(stroke
				(width 0.1)
				(type default)
			)
			(layer "F.Fab")
		)
		(fp_line
			(start -0.12065 0.3048)
			(end -0.67945 0.3048)
			(stroke
				(width 0.1)
				(type default)
			)
			(layer "F.Fab")
		)
		(fp_line
			(start 0.120396 0.3048)
			(end 0.120396 0.2794)
			(stroke
				(width 0.1)
				(type default)
			)
			(layer "F.Fab")
		)
		(fp_line
			(start 0.67945 0.3048)
			(end 0.120396 0.3048)
			(stroke
				(width 0.1)
				(type default)
			)
			(layer "F.Fab")
		)
		(fp_line
			(start -0.12065 0.2794)
			(end -0.12065 0.3048)
			(stroke
				(width 0.1)
				(type default)
			)
			(layer "F.Fab")
		)
		(fp_line
			(start 0.120396 0.2794)
			(end -0.12065 0.2794)
			(stroke
				(width 0.1)
				(type default)
			)
			(layer "F.Fab")
		)
		(fp_line
			(start -0.12065 -0.2794)
			(end 0.12065 -0.2794)
			(stroke
				(width 0.1)
				(type default)
			)
			(layer "F.Fab")
		)
		(fp_line
			(start 0.12065 -0.2794)
			(end 0.12065 -0.3048)
			(stroke
				(width 0.1)
				(type default)
			)
			(layer "F.Fab")
		)
		(fp_line
			(start 0.12065 -0.3048)
			(end 0.67945 -0.3048)
			(stroke
				(width 0.1)
				(type default)
			)
			(layer "F.Fab")
		)
		(fp_line
			(start 0.67945 -0.3048)
			(end 0.67945 0.3048)
			(stroke
				(width 0.1)
				(type default)
			)
			(layer "F.Fab")
		)
		(fp_line
			(start -0.67945 -0.305054)
			(end -0.12065 -0.305054)
			(stroke
				(width 0.1)
				(type default)
			)
			(layer "F.Fab")
		)
		(fp_line
			(start -0.12065 -0.305054)
			(end -0.12065 -0.2794)
			(stroke
				(width 0.1)
				(type default)
			)
			(layer "F.Fab")
		)
		(pad "1" smd circle
			(at -0.40005 0 270)
			(size 0 0)
			(layers "F.Cu" "F.Mask" "F.Paste")
			(net "P3V3_OCP_MODE_1")
		)
		(pad "2" smd circle
			(at 0.40005 0 270)
			(size 0 0)
			(layers "F.Cu" "F.Mask" "F.Paste")
			(net "GND")
		)
	)
	(footprint ""
		(layer "F.Cu")
		(at 426.979588 -391.49909 180)
		(property "Reference" "R1059"
			(at 0 0 180)
			(layer "F.SilkS")
			(hide yes)
			(effects
				(font
					(size 1.27 1.27)
				)
			)
		)
		(property "Value" ""
			(at 0 0 180)
			(layer "F.Fab")
			(effects
				(font
					(size 1.27 1.27)
				)
			)
		)
		(duplicate_pad_numbers_are_jumpers no)
		(fp_line
			(start 0.32512 0.175006)
			(end -0.32512 0.175006)
			(stroke
				(width 0.1)
				(type default)
			)
			(layer "F.Fab")
		)
		(fp_line
			(start 0.32512 -0.175006)
			(end 0.32512 0.175006)
			(stroke
				(width 0.1)
				(type default)
			)
			(layer "F.Fab")
		)
		(fp_line
			(start -0.32512 0.175006)
			(end -0.32512 -0.175006)
			(stroke
				(width 0.1)
				(type default)
			)
			(layer "F.Fab")
		)
		(fp_line
			(start -0.32512 -0.175006)
			(end 0.32512 -0.175006)
			(stroke
				(width 0.1)
				(type default)
			)
			(layer "F.Fab")
		)
		(pad "1" smd rect
			(at -0.2667 0 180)
			(size 0.3048 0.381)
			(layers "F.Cu" "F.Mask" "F.Paste")
			(net "P1V8_CPU0_RT_1D")
		)
		(pad "2" smd rect
			(at 0.2667 0)
			(size 0.3048 0.381)
			(layers "F.Cu" "F.Mask" "F.Paste")
			(net "RT_CPU0_P2_ADDR1")
		)
	)
	(footprint ""
		(layer "F.Cu")
		(at 171.20743 -101.998018)
		(property "Reference" "R6184"
			(at 0 0 0)
			(layer "F.SilkS")
			(hide yes)
			(effects
				(font
					(size 1.27 1.27)
				)
			)
		)
		(property "Value" ""
			(at 0 0 0)
			(layer "F.Fab")
			(effects
				(font
					(size 1.27 1.27)
				)
			)
		)
		(duplicate_pad_numbers_are_jumpers no)
		(fp_line
			(start -0.7874 -0.4064)
			(end 0.7874 -0.4064)
			(stroke
				(width 0.1524)
				(type default)
			)
			(layer "F.SilkS")
		)
		(fp_line
			(start -0.7874 0.4064)
			(end -0.7874 -0.4064)
			(stroke
				(width 0.1524)
				(type default)
			)
			(layer "F.SilkS")
		)
		(fp_line
			(start 0.7874 -0.4064)
			(end 0.7874 0.4064)
			(stroke
				(width 0.1524)
				(type default)
			)
			(layer "F.SilkS")
		)
		(fp_line
			(start 0.7874 0.4064)
			(end -0.7874 0.4064)
			(stroke
				(width 0.1524)
				(type default)
			)
			(layer "F.SilkS")
		)
		(fp_line
			(start -0.67945 -0.305054)
			(end -0.12065 -0.305054)
			(stroke
				(width 0.1)
				(type default)
			)
			(layer "F.Fab")
		)
		(fp_line
			(start -0.67945 0.3048)
			(end -0.67945 -0.305054)
			(stroke
				(width 0.1)
				(type default)
			)
			(layer "F.Fab")
		)
		(fp_line
			(start -0.12065 -0.305054)
			(end -0.12065 -0.2794)
			(stroke
				(width 0.1)
				(type default)
			)
			(layer "F.Fab")
		)
		(fp_line
			(start -0.12065 -0.2794)
			(end 0.12065 -0.2794)
			(stroke
				(width 0.1)
				(type default)
			)
			(layer "F.Fab")
		)
		(fp_line
			(start -0.12065 0.2794)
			(end -0.12065 0.3048)
			(stroke
				(width 0.1)
				(type default)
			)
			(layer "F.Fab")
		)
		(fp_line
			(start -0.12065 0.3048)
			(end -0.67945 0.3048)
			(stroke
				(width 0.1)
				(type default)
			)
			(layer "F.Fab")
		)
		(fp_line
			(start 0.120396 0.2794)
			(end -0.12065 0.2794)
			(stroke
				(width 0.1)
				(type default)
			)
			(layer "F.Fab")
		)
		(fp_line
			(start 0.120396 0.3048)
			(end 0.120396 0.2794)
			(stroke
				(width 0.1)
				(type default)
			)
			(layer "F.Fab")
		)
		(fp_line
			(start 0.12065 -0.3048)
			(end 0.67945 -0.3048)
			(stroke
				(width 0.1)
				(type default)
			)
			(layer "F.Fab")
		)
		(fp_line
			(start 0.12065 -0.2794)
			(end 0.12065 -0.3048)
			(stroke
				(width 0.1)
				(type default)
			)
			(layer "F.Fab")
		)
		(fp_line
			(start 0.67945 -0.3048)
			(end 0.67945 0.3048)
			(stroke
				(width 0.1)
				(type default)
			)
			(layer "F.Fab")
		)
		(fp_line
			(start 0.67945 0.3048)
			(end 0.120396 0.3048)
			(stroke
				(width 0.1)
				(type default)
			)
			(layer "F.Fab")
		)
		(pad "1" smd circle
			(at -0.40005 0)
			(size 0 0)
			(layers "F.Cu" "F.Mask" "F.Paste")
			(net "FM_SEC_MUX_SEL")
		)
		(pad "2" smd circle
			(at 0.40005 0)
			(size 0 0)
			(layers "F.Cu" "F.Mask" "F.Paste")
			(net "FM_SEC_MUX_R_SEL")
		)
	)
)
